(kicad_pcb
	(version 20260206)
	(generator "pcbnew")
	(generator_version "10.0")
	(general
		(thickness 1.6)
		(legacy_teardrops no)
	)
	(paper "A4")
	(title_block
		(title "Bryce Canyon_IOM_M2_16342-2_OCP.brd")
		(comment 1 "Bryce Canyon / footprint 69 of 1146 (U2), pads 346-456 of 456")
	)
	(layers
		(0 "F.Cu" signal "TOP")
		(4 "In1.Cu" signal "L2GND")
		(6 "In2.Cu" signal "L3")
		(8 "In3.Cu" signal "L4VCC")
		(10 "In4.Cu" signal "L5VCC")
		(12 "In5.Cu" signal "L6")
		(14 "In6.Cu" signal "L7GND")
		(2 "B.Cu" signal "BOTTOM")
		(9 "F.Adhes" user "F.Adhesive")
		(11 "B.Adhes" user "B.Adhesive")
		(13 "F.Paste" user "Package Geometry/Pastemask Top")
		(15 "B.Paste" user "Package Geometry/Pastemask Bottom")
		(5 "F.SilkS" user "Ref Des/Silkscreen Top")
		(7 "B.SilkS" user "Ref Des/Silkscreen Bottom")
		(1 "F.Mask" user "Board Geometry/Soldermask Top")
		(3 "B.Mask" user "Board Geometry/Soldermask Bottom")
		(17 "Dwgs.User" user "User.Drawings")
		(19 "Cmts.User" user "User.Comments")
		(21 "Eco1.User" user "User.Eco1")
		(23 "Eco2.User" user "User.Eco2")
		(25 "Edge.Cuts" user "Board Geometry/Outline")
		(27 "Margin" user)
		(31 "F.CrtYd" user "Package Geometry/Place Bound Top")
		(29 "B.CrtYd" user "Package Geometry/Place Bound Bottom")
		(35 "F.Fab" user "Ref Des/Assembly Top")
		(33 "B.Fab" user "Ref Des/Assembly Bottom")
	)
	(footprint ""
		(layer "F.Cu")
		(at 47.69993 -144.999964 -90)
		(property "Reference" "U2"
			(at 0 0 270)
			(layer "F.SilkS")
			(hide yes)
			(effects
				(font
					(size 1.27 1.27)
				)
			)
		)
		(property "Value" "AST2500A2-GP-GP-U"
			(at -17.0307 -8.584692 270)
			(unlocked yes)
			(layer "F.Fab")
			(hide yes)
			(effects
				(font
					(size 1.016 1.016)
					(thickness 0.1524)
				)
			)
		)
		(property "Device Type" "BGA456D19H58"
			(at -17.0307 -10.108692 270)
			(unlocked yes)
			(layer "F.Fab")
			(hide yes)
			(effects
				(font
					(size 1.016 1.016)
					(thickness 0.1524)
				)
			)
		)
		(duplicate_pad_numbers_are_jumpers no)
		(pad "R22" smd circle
			(at 8.400034 2.800096 270)
			(size 0.3556 0.3556)
			(layers "F.Cu" "F.Mask" "F.Paste")
			(net "BMC_GPIOY0")
		)
		(pad "T1" smd circle
			(at -8.400034 3.599942 270)
			(size 0.3556 0.3556)
			(layers "F.Cu" "F.Mask" "F.Paste")
			(net "TP_BMC_GPIOL1")
		)
		(pad "T2" smd circle
			(at -7.599934 3.599942 270)
			(size 0.3556 0.3556)
			(layers "F.Cu" "F.Mask" "F.Paste")
			(net "TP_BMC_GPIOL0")
		)
		(pad "T3" smd circle
			(at -6.800088 3.599942 270)
			(size 0.3556 0.3556)
			(layers "F.Cu" "F.Mask" "F.Paste")
			(net "IOM_TYPE3")
		)
		(pad "T4" smd circle
			(at -5.999988 3.599942 270)
			(size 0.3556 0.3556)
			(layers "F.Cu" "F.Mask" "F.Paste")
			(net "TP_BMC_GPION7")
		)
		(pad "T5" smd circle
			(at -5.199888 3.599942 270)
			(size 0.3556 0.3556)
			(layers "F.Cu" "F.Mask" "F.Paste")
			(net "UART_EXP_BMC_TX_R")
		)
		(pad "T6" smd circle
			(at -4.400042 3.599942 270)
			(size 0.3556 0.3556)
			(layers "F.Cu" "F.Mask" "F.Paste")
			(net "GND")
		)
		(pad "T7" smd circle
			(at -3.599942 3.599942 270)
			(size 0.3556 0.3556)
			(layers "F.Cu" "F.Mask" "F.Paste")
			(net "GND")
		)
		(pad "T8" smd circle
			(at -2.800096 3.599942 270)
			(size 0.3556 0.3556)
			(layers "F.Cu" "F.Mask" "F.Paste")
			(net "P1V2_STBY")
		)
		(pad "T9" smd circle
			(at -1.999996 3.599942 270)
			(size 0.3556 0.3556)
			(layers "F.Cu" "F.Mask" "F.Paste")
			(net "DDR_VREF")
		)
		(pad "T10" smd circle
			(at -1.199896 3.599942 270)
			(size 0.3556 0.3556)
			(layers "F.Cu" "F.Mask" "F.Paste")
			(net "P1V2_STBY")
		)
		(pad "T11" smd circle
			(at -0.40005 3.599942 270)
			(size 0.3556 0.3556)
			(layers "F.Cu" "F.Mask" "F.Paste")
			(net "MPLLAV33")
		)
		(pad "T12" smd circle
			(at 0.40005 3.599942 270)
			(size 0.3556 0.3556)
			(layers "F.Cu" "F.Mask" "F.Paste")
			(net "P1V2_STBY")
		)
		(pad "T13" smd circle
			(at 1.199896 3.599942 270)
			(size 0.3556 0.3556)
			(layers "F.Cu" "F.Mask" "F.Paste")
			(net "P1V2_STBY")
		)
		(pad "T14" smd circle
			(at 1.999996 3.599942 270)
			(size 0.3556 0.3556)
			(layers "F.Cu" "F.Mask" "F.Paste")
			(net "P1V2_STBY")
		)
		(pad "T15" smd circle
			(at 2.800096 3.599942 270)
			(size 0.3556 0.3556)
			(layers "F.Cu" "F.Mask" "F.Paste")
			(net "P3V3_STBY")
		)
		(pad "T16" smd circle
			(at 3.599942 3.599942 270)
			(size 0.3556 0.3556)
			(layers "F.Cu" "F.Mask" "F.Paste")
			(net "GND")
		)
		(pad "T17" smd circle
			(at 4.400042 3.599942 270)
			(size 0.3556 0.3556)
			(layers "F.Cu" "F.Mask" "F.Paste")
			(net "TP_BMC_GPIOR2")
		)
		(pad "T18" smd circle
			(at 5.199888 3.599942 270)
			(size 0.3556 0.3556)
			(layers "F.Cu" "F.Mask" "F.Paste")
			(net "BMC_SPI_MISO")
		)
		(pad "T19" smd circle
			(at 5.999988 3.599942 270)
			(size 0.3556 0.3556)
			(layers "F.Cu" "F.Mask" "F.Paste")
			(net "TP_BMC_GPIOR1")
		)
		(pad "T20" smd circle
			(at 6.800088 3.599942 270)
			(size 0.3556 0.3556)
			(layers "F.Cu" "F.Mask" "F.Paste")
			(net "Net_90")
		)
		(pad "T21" smd circle
			(at 7.599934 3.599942 270)
			(size 0.3556 0.3556)
			(layers "F.Cu" "F.Mask" "F.Paste")
			(net "IOM_FULL_PGOOD")
		)
		(pad "T22" smd circle
			(at 8.400034 3.599942 270)
			(size 0.3556 0.3556)
			(layers "F.Cu" "F.Mask" "F.Paste")
			(net "BMC_SELF_HW_RST")
		)
		(pad "U1" smd circle
			(at -8.400034 4.400042 270)
			(size 0.3556 0.3556)
			(layers "F.Cu" "F.Mask" "F.Paste")
			(net "TP_BMC_GPIOL2")
		)
		(pad "U2" smd circle
			(at -7.599934 4.400042 270)
			(size 0.3556 0.3556)
			(layers "F.Cu" "F.Mask" "F.Paste")
			(net "TP_BMC_GPIOL3")
		)
		(pad "U3" smd circle
			(at -6.800088 4.400042 270)
			(size 0.3556 0.3556)
			(layers "F.Cu" "F.Mask" "F.Paste")
			(net "TP_BMC_GPION3")
		)
		(pad "U4" smd circle
			(at -5.999988 4.400042 270)
			(size 0.3556 0.3556)
			(layers "F.Cu" "F.Mask" "F.Paste")
			(net "BMC_LOC_HB")
		)
		(pad "U5" smd circle
			(at -5.199888 4.400042 270)
			(size 0.3556 0.3556)
			(layers "F.Cu" "F.Mask" "F.Paste")
			(net "BMC_RMT_HB")
		)
		(pad "U6" smd circle
			(at -4.400042 4.400042 270)
			(size 0.3556 0.3556)
			(layers "F.Cu" "F.Mask" "F.Paste")
			(net "GND")
		)
		(pad "U7" smd circle
			(at -3.599942 4.400042 270)
			(size 0.3556 0.3556)
			(layers "F.Cu" "F.Mask" "F.Paste")
			(net "MEMDQ_15")
		)
		(pad "U8" smd circle
			(at -2.800096 4.400042 270)
			(size 0.3556 0.3556)
			(layers "F.Cu" "F.Mask" "F.Paste")
			(net "MEMDM_0")
		)
		(pad "U9" smd circle
			(at -1.999996 4.400042 270)
			(size 0.3556 0.3556)
			(layers "F.Cu" "F.Mask" "F.Paste")
			(net "MEMDQ_4")
		)
		(pad "U10" smd circle
			(at -1.199896 4.400042 270)
			(size 0.3556 0.3556)
			(layers "F.Cu" "F.Mask" "F.Paste")
			(net "MEMDQ_0")
		)
		(pad "U11" smd circle
			(at -0.40005 4.400042 270)
			(size 0.3556 0.3556)
			(layers "F.Cu" "F.Mask" "F.Paste")
			(net "GND")
		)
		(pad "U12" smd circle
			(at 0.40005 4.400042 270)
			(size 0.3556 0.3556)
			(layers "F.Cu" "F.Mask" "F.Paste")
			(net "MEMBA_0")
		)
		(pad "U13" smd circle
			(at 1.199896 4.400042 270)
			(size 0.3556 0.3556)
			(layers "F.Cu" "F.Mask" "F.Paste")
			(net "MEMA_10")
		)
		(pad "U14" smd circle
			(at 1.999996 4.400042 270)
			(size 0.3556 0.3556)
			(layers "F.Cu" "F.Mask" "F.Paste")
			(net "MEMA_3")
		)
		(pad "U15" smd circle
			(at 2.800096 4.400042 270)
			(size 0.3556 0.3556)
			(layers "F.Cu" "F.Mask" "F.Paste")
			(net "Net_556")
		)
		(pad "U16" smd circle
			(at 3.599942 4.400042 270)
			(size 0.3556 0.3556)
			(layers "F.Cu" "F.Mask" "F.Paste")
			(net "DDR4_ALERT")
		)
		(pad "U17" smd circle
			(at 4.400042 4.400042 270)
			(size 0.3556 0.3556)
			(layers "F.Cu" "F.Mask" "F.Paste")
			(net "BMC_SPI_MOSI")
		)
		(pad "U18" smd circle
			(at 5.199888 4.400042 270)
			(size 0.3556 0.3556)
			(layers "F.Cu" "F.Mask" "F.Paste")
			(net "BMC0_SRST_N")
		)
		(pad "U19" smd circle
			(at 5.999988 4.400042 270)
			(size 0.3556 0.3556)
			(layers "F.Cu" "F.Mask" "F.Paste")
			(net "BMC_UART_SEL_OUT")
		)
		(pad "U20" smd circle
			(at 6.800088 4.400042 270)
			(size 0.3556 0.3556)
			(layers "F.Cu" "F.Mask" "F.Paste")
			(net "BMC_GPIOS6")
		)
		(pad "U21" smd circle
			(at 7.599934 4.400042 270)
			(size 0.3556 0.3556)
			(layers "F.Cu" "F.Mask" "F.Paste")
			(net "BMC_GPIOZ4")
		)
		(pad "U22" smd circle
			(at 8.400034 4.400042 270)
			(size 0.3556 0.3556)
			(layers "F.Cu" "F.Mask" "F.Paste")
			(net "Net_5")
		)
		(pad "V1" smd circle
			(at -8.400034 5.199888 270)
			(size 0.3556 0.3556)
			(layers "F.Cu" "F.Mask" "F.Paste")
			(net "UART_BMC_COMP_IN_RX")
		)
		(pad "V2" smd circle
			(at -7.599934 5.199888 270)
			(size 0.3556 0.3556)
			(layers "F.Cu" "F.Mask" "F.Paste")
			(net "FAN_PWM0_BMC")
		)
		(pad "V3" smd circle
			(at -6.800088 5.199888 270)
			(size 0.3556 0.3556)
			(layers "F.Cu" "F.Mask" "F.Paste")
			(net "TP_BMC_GPION2")
		)
		(pad "V4" smd circle
			(at -5.999988 5.199888 270)
			(size 0.3556 0.3556)
			(layers "F.Cu" "F.Mask" "F.Paste")
			(net "DEBUG_GPIO_BMC_R_6")
		)
		(pad "V5" smd circle
			(at -5.199888 5.199888 270)
			(size 0.3556 0.3556)
			(layers "F.Cu" "F.Mask" "F.Paste")
			(net "FLA0_WP_N_R")
		)
		(pad "V6" smd circle
			(at -4.400042 5.199888 270)
			(size 0.3556 0.3556)
			(layers "F.Cu" "F.Mask" "F.Paste")
			(net "DEBUG_GPIO_BMC_R_5")
		)
		(pad "V7" smd circle
			(at -3.599942 5.199888 270)
			(size 0.3556 0.3556)
			(layers "F.Cu" "F.Mask" "F.Paste")
			(net "MEMDQ_14")
		)
		(pad "V8" smd circle
			(at -2.800096 5.199888 270)
			(size 0.3556 0.3556)
			(layers "F.Cu" "F.Mask" "F.Paste")
			(net "GND")
		)
		(pad "V9" smd circle
			(at -1.999996 5.199888 270)
			(size 0.3556 0.3556)
			(layers "F.Cu" "F.Mask" "F.Paste")
			(net "MEMDQ_7")
		)
		(pad "V10" smd circle
			(at -1.199896 5.199888 270)
			(size 0.3556 0.3556)
			(layers "F.Cu" "F.Mask" "F.Paste")
			(net "GND")
		)
		(pad "V11" smd circle
			(at -0.40005 5.199888 270)
			(size 0.3556 0.3556)
			(layers "F.Cu" "F.Mask" "F.Paste")
			(net "MEMODT")
		)
		(pad "V12" smd circle
			(at 0.40005 5.199888 270)
			(size 0.3556 0.3556)
			(layers "F.Cu" "F.Mask" "F.Paste")
			(net "GND")
		)
		(pad "V13" smd circle
			(at 1.199896 5.199888 270)
			(size 0.3556 0.3556)
			(layers "F.Cu" "F.Mask" "F.Paste")
			(net "MEMA_0")
		)
		(pad "V14" smd circle
			(at 1.999996 5.199888 270)
			(size 0.3556 0.3556)
			(layers "F.Cu" "F.Mask" "F.Paste")
			(net "GND")
		)
		(pad "V15" smd circle
			(at 2.800096 5.199888 270)
			(size 0.3556 0.3556)
			(layers "F.Cu" "F.Mask" "F.Paste")
			(net "MEMA_5")
		)
		(pad "V16" smd circle
			(at 3.599942 5.199888 270)
			(size 0.3556 0.3556)
			(layers "F.Cu" "F.Mask" "F.Paste")
			(net "GND")
		)
		(pad "V17" smd circle
			(at 4.400042 5.199888 270)
			(size 0.3556 0.3556)
			(layers "F.Cu" "F.Mask" "F.Paste")
			(net "P1V15_STBY")
		)
		(pad "V18" smd circle
			(at 5.199888 5.199888 270)
			(size 0.3556 0.3556)
			(layers "F.Cu" "F.Mask" "F.Paste")
			(net "BMC_EXTRST_N")
		)
		(pad "V19" smd circle
			(at 5.999988 5.199888 270)
			(size 0.3556 0.3556)
			(layers "F.Cu" "F.Mask" "F.Paste")
			(net "TP_BMC_GPIOR5")
		)
		(pad "V20" smd circle
			(at 6.800088 5.199888 270)
			(size 0.3556 0.3556)
			(layers "F.Cu" "F.Mask" "F.Paste")
			(net "EXP_UART_EN")
		)
		(pad "V21" smd circle
			(at 7.599934 5.199888 270)
			(size 0.3556 0.3556)
			(layers "F.Cu" "F.Mask" "F.Paste")
			(net "CONN_A_PRSNTA")
		)
		(pad "V22" smd circle
			(at 8.400034 5.199888 270)
			(size 0.3556 0.3556)
			(layers "F.Cu" "F.Mask" "F.Paste")
			(net "BMC_GPIOZ6")
		)
		(pad "W1" smd circle
			(at -8.400034 5.999988 270)
			(size 0.3556 0.3556)
			(layers "F.Cu" "F.Mask" "F.Paste")
			(net "UART_COMP_OUT_TX_R")
		)
		(pad "W2" smd circle
			(at -7.599934 5.999988 270)
			(size 0.3556 0.3556)
			(layers "F.Cu" "F.Mask" "F.Paste")
			(net "FAN_PWM1_BMC")
		)
		(pad "W3" smd circle
			(at -6.800088 5.999988 270)
			(size 0.3556 0.3556)
			(layers "F.Cu" "F.Mask" "F.Paste")
			(net "TP_BMC_GPION4")
		)
		(pad "W4" smd circle
			(at -5.999988 5.999988 270)
			(size 0.3556 0.3556)
			(layers "F.Cu" "F.Mask" "F.Paste")
			(net "COMP_PWR_EN_R")
		)
		(pad "W5" smd circle
			(at -5.199888 5.999988 270)
			(size 0.3556 0.3556)
			(layers "F.Cu" "F.Mask" "F.Paste")
			(net "Net_107")
		)
		(pad "W6" smd circle
			(at -4.400042 5.999988 270)
			(size 0.3556 0.3556)
			(layers "F.Cu" "F.Mask" "F.Paste")
			(net "DEBUG_GPIO_BMC_R_4")
		)
		(pad "W7" smd circle
			(at -3.599942 5.999988 270)
			(size 0.3556 0.3556)
			(layers "F.Cu" "F.Mask" "F.Paste")
			(net "MEMDQ_13")
		)
		(pad "W8" smd circle
			(at -2.800096 5.999988 270)
			(size 0.3556 0.3556)
			(layers "F.Cu" "F.Mask" "F.Paste")
			(net "MEMDQ_11")
		)
		(pad "W9" smd circle
			(at -1.999996 5.999988 270)
			(size 0.3556 0.3556)
			(layers "F.Cu" "F.Mask" "F.Paste")
			(net "MEMDQ_6")
		)
		(pad "W10" smd circle
			(at -1.199896 5.999988 270)
			(size 0.3556 0.3556)
			(layers "F.Cu" "F.Mask" "F.Paste")
			(net "MEMDQ_1")
		)
		(pad "W11" smd circle
			(at -0.40005 5.999988 270)
			(size 0.3556 0.3556)
			(layers "F.Cu" "F.Mask" "F.Paste")
			(net "MIOZ")
		)
		(pad "W12" smd circle
			(at 0.40005 5.999988 270)
			(size 0.3556 0.3556)
			(layers "F.Cu" "F.Mask" "F.Paste")
			(net "MEMRASN")
		)
		(pad "W13" smd circle
			(at 1.199896 5.999988 270)
			(size 0.3556 0.3556)
			(layers "F.Cu" "F.Mask" "F.Paste")
			(net "MEMBG_0")
		)
		(pad "W14" smd circle
			(at 1.999996 5.999988 270)
			(size 0.3556 0.3556)
			(layers "F.Cu" "F.Mask" "F.Paste")
			(net "MEMA_2")
		)
		(pad "W15" smd circle
			(at 2.800096 5.999988 270)
			(size 0.3556 0.3556)
			(layers "F.Cu" "F.Mask" "F.Paste")
			(net "MEMA_4")
		)
		(pad "W16" smd circle
			(at 3.599942 5.999988 270)
			(size 0.3556 0.3556)
			(layers "F.Cu" "F.Mask" "F.Paste")
			(net "MEMA_8")
		)
		(pad "W17" smd circle
			(at 4.400042 5.999988 270)
			(size 0.3556 0.3556)
			(layers "F.Cu" "F.Mask" "F.Paste")
			(net "MPLLAV33")
		)
		(pad "W18" smd circle
			(at 5.199888 5.999988 270)
			(size 0.3556 0.3556)
			(layers "F.Cu" "F.Mask" "F.Paste")
			(net "CLKIN_24M_BMC")
		)
		(pad "W19" smd circle
			(at 5.999988 5.999988 270)
			(size 0.3556 0.3556)
			(layers "F.Cu" "F.Mask" "F.Paste")
			(net "TP_BMC_GPIOR4")
		)
		(pad "W20" smd circle
			(at 6.800088 5.999988 270)
			(size 0.3556 0.3556)
			(layers "F.Cu" "F.Mask" "F.Paste")
			(net "BMC_GPIOS5")
		)
		(pad "W21" smd circle
			(at 7.599934 5.999988 270)
			(size 0.3556 0.3556)
			(layers "F.Cu" "F.Mask" "F.Paste")
			(net "BMC_GPIOZ7")
		)
		(pad "W22" smd circle
			(at 8.400034 5.999988 270)
			(size 0.3556 0.3556)
			(layers "F.Cu" "F.Mask" "F.Paste")
			(net "BMC_GPIOZ5")
		)
		(pad "Y1" smd circle
			(at -8.400034 6.800088 270)
			(size 0.4064 0.4064)
			(layers "F.Cu" "F.Mask" "F.Paste")
			(net "Net_565")
		)
		(pad "Y2" smd circle
			(at -7.599934 6.800088 270)
			(size 0.4064 0.4064)
			(layers "F.Cu" "F.Mask" "F.Paste")
			(net "Net_564")
		)
		(pad "Y3" smd circle
			(at -6.800088 6.800088 270)
			(size 0.4064 0.4064)
			(layers "F.Cu" "F.Mask" "F.Paste")
			(net "TP_BMC_GPION6")
		)
		(pad "Y4" smd circle
			(at -5.999988 6.800088 270)
			(size 0.3556 0.3556)
			(layers "F.Cu" "F.Mask" "F.Paste")
			(net "SCC_B_HB_IN_R")
		)
		(pad "Y5" smd circle
			(at -5.199888 6.800088 270)
			(size 0.3556 0.3556)
			(layers "F.Cu" "F.Mask" "F.Paste")
			(net "DEBUG_GPIO_BMC_R_3")
		)
		(pad "Y6" smd circle
			(at -4.400042 6.800088 270)
			(size 0.3556 0.3556)
			(layers "F.Cu" "F.Mask" "F.Paste")
			(net "DEBUG_GPIO_BMC_R_2")
		)
		(pad "Y7" smd circle
			(at -3.599942 6.800088 270)
			(size 0.3556 0.3556)
			(layers "F.Cu" "F.Mask" "F.Paste")
			(net "MEMDQ_10")
		)
		(pad "Y8" smd circle
			(at -2.800096 6.800088 270)
			(size 0.3556 0.3556)
			(layers "F.Cu" "F.Mask" "F.Paste")
			(net "MEMDQ_9")
		)
		(pad "Y9" smd circle
			(at -1.999996 6.800088 270)
			(size 0.3556 0.3556)
			(layers "F.Cu" "F.Mask" "F.Paste")
			(net "MEMDQ_5")
		)
		(pad "Y10" smd circle
			(at -1.199896 6.800088 270)
			(size 0.3556 0.3556)
			(layers "F.Cu" "F.Mask" "F.Paste")
			(net "MEMDQ_2")
		)
		(pad "Y11" smd circle
			(at -0.40005 6.800088 270)
			(size 0.3556 0.3556)
			(layers "F.Cu" "F.Mask" "F.Paste")
			(net "MEMCKE")
		)
		(pad "Y12" smd circle
			(at 0.40005 6.800088 270)
			(size 0.3556 0.3556)
			(layers "F.Cu" "F.Mask" "F.Paste")
			(net "MEMWEN")
		)
		(pad "Y13" smd circle
			(at 1.199896 6.800088 270)
			(size 0.3556 0.3556)
			(layers "F.Cu" "F.Mask" "F.Paste")
			(net "MEMBA_1")
		)
		(pad "Y14" smd circle
			(at 1.999996 6.800088 270)
			(size 0.3556 0.3556)
			(layers "F.Cu" "F.Mask" "F.Paste")
			(net "MEMA_12")
		)
		(pad "Y15" smd circle
			(at 2.800096 6.800088 270)
			(size 0.3556 0.3556)
			(layers "F.Cu" "F.Mask" "F.Paste")
			(net "DDR4_ACT")
		)
		(pad "Y16" smd circle
			(at 3.599942 6.800088 270)
			(size 0.3556 0.3556)
			(layers "F.Cu" "F.Mask" "F.Paste")
			(net "MEMA_9")
		)
		(pad "Y17" smd circle
			(at 4.400042 6.800088 270)
			(size 0.3556 0.3556)
			(layers "F.Cu" "F.Mask" "F.Paste")
			(net "MPLLAV33")
		)
		(pad "Y18" smd circle
			(at 5.199888 6.800088 270)
			(size 0.3556 0.3556)
			(layers "F.Cu" "F.Mask" "F.Paste")
			(net "BMC_HBLED")
		)
		(pad "Y19" smd circle
			(at 5.999988 6.800088 270)
			(size 0.3556 0.3556)
			(layers "F.Cu" "F.Mask" "F.Paste")
			(net "TP_BMC_GPIOR3")
		)
		(pad "Y20" smd circle
			(at 6.800088 6.800088 270)
			(size 0.4064 0.4064)
			(layers "F.Cu" "F.Mask" "F.Paste")
			(net "DEBUG_RST_BTN_N")
		)
		(pad "Y21" smd circle
			(at 7.599934 6.800088 270)
			(size 0.4064 0.4064)
			(layers "F.Cu" "F.Mask" "F.Paste")
			(net "Net_80")
		)
		(pad "Y22" smd circle
			(at 8.400034 6.800088 270)
			(size 0.4064 0.4064)
			(layers "F.Cu" "F.Mask" "F.Paste")
			(net "Net_4")
		)
	)
)
